# T6G (Grand Teton) — schematic netlist excerpt (pin names and nets, part order shuffled) for the footprints in the layout excerpt that follows; sources: Cadence DE-HDL packaged netlist, KiCad conversion of 04192023_DAF0TMB3IC0_F0TG_MB_C_brd_V02_OCP.brd

R4178  Q_RES  33.2 1% CHIP  pkg 0402LF  page 235 : A = SMB_LM75_2_3V3AUX_SCL ; B = SMB_LM75_2_3V3AUX_SCL_R1
C1517  Q_CAP  0.1UF 16V 10% X7R  pkg C0402  page 173 : A = PVDD18_S5_P1 ; B = GND

(kicad_pcb
	(version 20260206)
	(generator "pcbnew")
	(generator_version "10.0")
	(general
		(thickness 1.6)
		(legacy_teardrops no)
	)
	(paper "A4")
	(title_block
		(title "04192023_DAF0TMB3IC0_F0TG_MB_C_brd_V02_OCP.brd")
		(comment 1 "Grand Teton / footprints 3407-3408 of 8354")
	)
	(layers
		(0 "F.Cu" signal "TOP")
		(4 "In1.Cu" signal "GND")
		(6 "In2.Cu" signal "IN1")
		(8 "In3.Cu" signal "GND1")
		(10 "In4.Cu" signal "IN2")
		(12 "In5.Cu" signal "GND2")
		(14 "In6.Cu" signal "IN3")
		(16 "In7.Cu" signal "GND3")
		(18 "In8.Cu" signal "VCC")
		(20 "In9.Cu" signal "VCC1")
		(22 "In10.Cu" signal "GND4")
		(24 "In11.Cu" signal "IN4")
		(26 "In12.Cu" signal "GND5")
		(28 "In13.Cu" signal "IN5")
		(30 "In14.Cu" signal "GND6")
		(32 "In15.Cu" signal "IN6")
		(34 "In16.Cu" signal "GND7")
		(2 "B.Cu" signal "BOTTOM")
		(9 "F.Adhes" user "F.Adhesive")
		(11 "B.Adhes" user "B.Adhesive")
		(13 "F.Paste" user "Package Geometry/Pastemask Top")
		(15 "B.Paste" user "Package Geometry/Pastemask Bottom")
		(5 "F.SilkS" user "Ref Des/Silkscreen Top")
		(7 "B.SilkS" user "Ref Des/Silkscreen Bottom")
		(1 "F.Mask" user "Board Geometry/Soldermask Top")
		(3 "B.Mask" user "Board Geometry/Soldermask Bottom")
		(17 "Dwgs.User" user "User.Drawings")
		(19 "Cmts.User" user "User.Comments")
		(21 "Eco1.User" user "User.Eco1")
		(23 "Eco2.User" user "User.Eco2")
		(25 "Edge.Cuts" user "Board Geometry/Outline")
		(27 "Margin" user)
		(31 "F.CrtYd" user "Package Geometry/Place Bound Top")
		(29 "B.CrtYd" user "Package Geometry/Place Bound Bottom")
		(35 "F.Fab" user "Ref Des/Assembly Top")
		(33 "B.Fab" user "Ref Des/Assembly Bottom")
	)
	(footprint ""
		(layer "F.Cu")
		(at 99.015296 -412.931102 90)
		(property "Reference" "R4178"
			(at 0 0 90)
			(layer "F.SilkS")
			(hide yes)
			(effects
				(font
					(size 1.27 1.27)
				)
			)
		)
		(property "Value" ""
			(at 0 0 90)
			(layer "F.Fab")
			(effects
				(font
					(size 1.27 1.27)
				)
			)
		)
		(duplicate_pad_numbers_are_jumpers no)
		(fp_line
			(start 0.7874 -0.4064)
			(end 0.7874 0.4064)
			(stroke
				(width 0.1524)
				(type default)
			)
			(layer "F.SilkS")
		)
		(fp_line
			(start -0.7874 -0.4064)
			(end 0.7874 -0.4064)
			(stroke
				(width 0.1524)
				(type default)
			)
			(layer "F.SilkS")
		)
		(fp_line
			(start 0.7874 0.4064)
			(end -0.7874 0.4064)
			(stroke
				(width 0.1524)
				(type default)
			)
			(layer "F.SilkS")
		)
		(fp_line
			(start -0.7874 0.4064)
			(end -0.7874 -0.4064)
			(stroke
				(width 0.1524)
				(type default)
			)
			(layer "F.SilkS")
		)
		(fp_line
			(start -0.12065 -0.305054)
			(end -0.12065 -0.2794)
			(stroke
				(width 0.1)
				(type default)
			)
			(layer "F.Fab")
		)
		(fp_line
			(start -0.67945 -0.305054)
			(end -0.12065 -0.305054)
			(stroke
				(width 0.1)
				(type default)
			)
			(layer "F.Fab")
		)
		(fp_line
			(start 0.67945 -0.3048)
			(end 0.67945 0.3048)
			(stroke
				(width 0.1)
				(type default)
			)
			(layer "F.Fab")
		)
		(fp_line
			(start 0.12065 -0.3048)
			(end 0.67945 -0.3048)
			(stroke
				(width 0.1)
				(type default)
			)
			(layer "F.Fab")
		)
		(fp_line
			(start 0.12065 -0.2794)
			(end 0.12065 -0.3048)
			(stroke
				(width 0.1)
				(type default)
			)
			(layer "F.Fab")
		)
		(fp_line
			(start -0.12065 -0.2794)
			(end 0.12065 -0.2794)
			(stroke
				(width 0.1)
				(type default)
			)
			(layer "F.Fab")
		)
		(fp_line
			(start 0.120396 0.2794)
			(end -0.12065 0.2794)
			(stroke
				(width 0.1)
				(type default)
			)
			(layer "F.Fab")
		)
		(fp_line
			(start -0.12065 0.2794)
			(end -0.12065 0.3048)
			(stroke
				(width 0.1)
				(type default)
			)
			(layer "F.Fab")
		)
		(fp_line
			(start 0.67945 0.3048)
			(end 0.120396 0.3048)
			(stroke
				(width 0.1)
				(type default)
			)
			(layer "F.Fab")
		)
		(fp_line
			(start 0.120396 0.3048)
			(end 0.120396 0.2794)
			(stroke
				(width 0.1)
				(type default)
			)
			(layer "F.Fab")
		)
		(fp_line
			(start -0.12065 0.3048)
			(end -0.67945 0.3048)
			(stroke
				(width 0.1)
				(type default)
			)
			(layer "F.Fab")
		)
		(fp_line
			(start -0.67945 0.3048)
			(end -0.67945 -0.305054)
			(stroke
				(width 0.1)
				(type default)
			)
			(layer "F.Fab")
		)
		(pad "1" smd circle
			(at -0.40005 0 90)
			(size 0 0)
			(layers "F.Cu" "F.Mask" "F.Paste")
			(net "SMB_LM75_2_3V3AUX_SCL")
		)
		(pad "2" smd circle
			(at 0.40005 0 90)
			(size 0 0)
			(layers "F.Cu" "F.Mask" "F.Paste")
			(net "SMB_LM75_2_3V3AUX_SCL_R1")
		)
	)
	(footprint ""
		(layer "F.Cu")
		(at 276.481794 -94.789498 180)
		(property "Reference" "C1517"
			(at 0 0 180)
			(layer "F.SilkS")
			(hide yes)
			(effects
				(font
					(size 1.27 1.27)
				)
			)
		)
		(property "Value" ""
			(at 0 0 180)
			(layer "F.Fab")
			(effects
				(font
					(size 1.27 1.27)
				)
			)
		)
		(duplicate_pad_numbers_are_jumpers no)
		(fp_line
			(start 0.7874 0.4064)
			(end -0.7874 0.4064)
			(stroke
				(width 0.1524)
				(type default)
			)
			(layer "F.SilkS")
		)
		(fp_line
			(start 0.7874 -0.4064)
			(end 0.7874 0.4064)
			(stroke
				(width 0.1524)
				(type default)
			)
			(layer "F.SilkS")
		)
		(fp_line
			(start -0.7874 0.4064)
			(end -0.7874 -0.4064)
			(stroke
				(width 0.1524)
				(type default)
			)
			(layer "F.SilkS")
		)
		(fp_line
			(start -0.7874 -0.4064)
			(end 0.7874 -0.4064)
			(stroke
				(width 0.1524)
				(type default)
			)
			(layer "F.SilkS")
		)
		(fp_line
			(start 0.67945 0.3048)
			(end 0.120396 0.3048)
			(stroke
				(width 0.1)
				(type default)
			)
			(layer "F.Fab")
		)
		(fp_line
			(start 0.67945 -0.3048)
			(end 0.67945 0.3048)
			(stroke
				(width 0.1)
				(type default)
			)
			(layer "F.Fab")
		)
		(fp_line
			(start 0.12065 -0.2794)
			(end 0.12065 -0.3048)
			(stroke
				(width 0.1)
				(type default)
			)
			(layer "F.Fab")
		)
		(fp_line
			(start 0.12065 -0.3048)
			(end 0.67945 -0.3048)
			(stroke
				(width 0.1)
				(type default)
			)
			(layer "F.Fab")
		)
		(fp_line
			(start 0.120396 0.3048)
			(end 0.120396 0.2794)
			(stroke
				(width 0.1)
				(type default)
			)
			(layer "F.Fab")
		)
		(fp_line
			(start 0.120396 0.2794)
			(end -0.12065 0.2794)
			(stroke
				(width 0.1)
				(type default)
			)
			(layer "F.Fab")
		)
		(fp_line
			(start -0.12065 0.3048)
			(end -0.67945 0.3048)
			(stroke
				(width 0.1)
				(type default)
			)
			(layer "F.Fab")
		)
		(fp_line
			(start -0.12065 0.2794)
			(end -0.12065 0.3048)
			(stroke
				(width 0.1)
				(type default)
			)
			(layer "F.Fab")
		)
		(fp_line
			(start -0.12065 -0.2794)
			(end 0.12065 -0.2794)
			(stroke
				(width 0.1)
				(type default)
			)
			(layer "F.Fab")
		)
		(fp_line
			(start -0.12065 -0.305054)
			(end -0.12065 -0.2794)
			(stroke
				(width 0.1)
				(type default)
			)
			(layer "F.Fab")
		)
		(fp_line
			(start -0.67945 0.3048)
			(end -0.67945 -0.305054)
			(stroke
				(width 0.1)
				(type default)
			)
			(layer "F.Fab")
		)
		(fp_line
			(start -0.67945 -0.305054)
			(end -0.12065 -0.305054)
			(stroke
				(width 0.1)
				(type default)
			)
			(layer "F.Fab")
		)
		(pad "1" smd circle
			(at -0.40005 0 180)
			(size 0 0)
			(layers "F.Cu" "F.Mask" "F.Paste")
			(net "PVDD18_S5_P1")
		)
		(pad "2" smd circle
			(at 0.40005 0 180)
			(size 0 0)
			(layers "F.Cu" "F.Mask" "F.Paste")
			(net "GND")
		)
	)
)
